# S9S_MB_2U (Grand Teton) — schematic netlist excerpt (pin names and nets, part order shuffled) for the footprints in the layout excerpt that follows; sources: Cadence DE-HDL packaged netlist, KiCad conversion of 03242023_DA0F0TMBIJ0_F0T_Motherboard_J_brd_V01_OCP.brd

X36  TP_TDR_4P_FTS  TP_TDR_4P_DIP EMPTY  pkg TH  page 310
  S1  = UNNAMED_310_TPTDR4PFTS_I10_S2
  P1  = T1_GND
  P2  = T1_GND
  S2  = UNNAMED_310_TPTDR4PFTS_I10_S1

PR558  Q_RES  100 1% CHIP  pkg 0402LF  page 296 : A = VSENSE_PVCCD_HV_CPU1_DN ; B = GND

(kicad_pcb
	(version 20260206)
	(generator "pcbnew")
	(generator_version "10.0")
	(general
		(thickness 1.6)
		(legacy_teardrops no)
	)
	(paper "A4")
	(title_block
		(title "03242023_DA0F0TMBIJ0_F0T_Motherboard_J_brd_V01_OCP.brd")
		(comment 1 "Grand Teton / footprints 3220-3221 of 6105")
	)
	(layers
		(0 "F.Cu" signal "TOP")
		(4 "In1.Cu" signal "GND")
		(6 "In2.Cu" signal "IN1")
		(8 "In3.Cu" signal "GND1")
		(10 "In4.Cu" signal "IN2")
		(12 "In5.Cu" signal "GND2")
		(14 "In6.Cu" signal "IN3")
		(16 "In7.Cu" signal "GND3")
		(18 "In8.Cu" signal "VCC")
		(20 "In9.Cu" signal "VCC1")
		(22 "In10.Cu" signal "GND4")
		(24 "In11.Cu" signal "IN4")
		(26 "In12.Cu" signal "GND5")
		(28 "In13.Cu" signal "IN5")
		(30 "In14.Cu" signal "GND6")
		(32 "In15.Cu" signal "IN6")
		(34 "In16.Cu" signal "GND7")
		(2 "B.Cu" signal "BOTTOM")
		(9 "F.Adhes" user "F.Adhesive")
		(11 "B.Adhes" user "B.Adhesive")
		(13 "F.Paste" user "Package Geometry/Pastemask Top")
		(15 "B.Paste" user "Package Geometry/Pastemask Bottom")
		(5 "F.SilkS" user "Ref Des/Silkscreen Top")
		(7 "B.SilkS" user "Ref Des/Silkscreen Bottom")
		(1 "F.Mask" user "Board Geometry/Soldermask Top")
		(3 "B.Mask" user "Board Geometry/Soldermask Bottom")
		(17 "Dwgs.User" user "User.Drawings")
		(19 "Cmts.User" user "User.Comments")
		(21 "Eco1.User" user "User.Eco1")
		(23 "Eco2.User" user "User.Eco2")
		(25 "Edge.Cuts" user "Board Geometry/Outline")
		(27 "Margin" user)
		(31 "F.CrtYd" user "Package Geometry/Place Bound Top")
		(29 "B.CrtYd" user "Package Geometry/Place Bound Bottom")
		(35 "F.Fab" user "Ref Des/Assembly Top")
		(33 "B.Fab" user "Ref Des/Assembly Bottom")
	)
	(footprint ""
		(layer "F.Cu")
		(at 73.94448 -160.212278 180)
		(property "Reference" "PR558"
			(at 0 0 180)
			(layer "F.SilkS")
			(hide yes)
			(effects
				(font
					(size 1.27 1.27)
				)
			)
		)
		(property "Value" ""
			(at 0 0 180)
			(layer "F.Fab")
			(effects
				(font
					(size 1.27 1.27)
				)
			)
		)
		(duplicate_pad_numbers_are_jumpers no)
		(fp_line
			(start 0.7874 0.4064)
			(end -0.7874 0.4064)
			(stroke
				(width 0.1524)
				(type default)
			)
			(layer "F.SilkS")
		)
		(fp_line
			(start 0.7874 -0.4064)
			(end 0.7874 0.4064)
			(stroke
				(width 0.1524)
				(type default)
			)
			(layer "F.SilkS")
		)
		(fp_line
			(start -0.7874 0.4064)
			(end -0.7874 -0.4064)
			(stroke
				(width 0.1524)
				(type default)
			)
			(layer "F.SilkS")
		)
		(fp_line
			(start -0.7874 -0.4064)
			(end 0.7874 -0.4064)
			(stroke
				(width 0.1524)
				(type default)
			)
			(layer "F.SilkS")
		)
		(fp_line
			(start 0.67945 0.3048)
			(end 0.120396 0.3048)
			(stroke
				(width 0.1)
				(type default)
			)
			(layer "F.Fab")
		)
		(fp_line
			(start 0.67945 -0.3048)
			(end 0.67945 0.3048)
			(stroke
				(width 0.1)
				(type default)
			)
			(layer "F.Fab")
		)
		(fp_line
			(start 0.12065 -0.2794)
			(end 0.12065 -0.3048)
			(stroke
				(width 0.1)
				(type default)
			)
			(layer "F.Fab")
		)
		(fp_line
			(start 0.12065 -0.3048)
			(end 0.67945 -0.3048)
			(stroke
				(width 0.1)
				(type default)
			)
			(layer "F.Fab")
		)
		(fp_line
			(start 0.120396 0.3048)
			(end 0.120396 0.2794)
			(stroke
				(width 0.1)
				(type default)
			)
			(layer "F.Fab")
		)
		(fp_line
			(start 0.120396 0.2794)
			(end -0.12065 0.2794)
			(stroke
				(width 0.1)
				(type default)
			)
			(layer "F.Fab")
		)
		(fp_line
			(start -0.12065 0.3048)
			(end -0.67945 0.3048)
			(stroke
				(width 0.1)
				(type default)
			)
			(layer "F.Fab")
		)
		(fp_line
			(start -0.12065 0.2794)
			(end -0.12065 0.3048)
			(stroke
				(width 0.1)
				(type default)
			)
			(layer "F.Fab")
		)
		(fp_line
			(start -0.12065 -0.2794)
			(end 0.12065 -0.2794)
			(stroke
				(width 0.1)
				(type default)
			)
			(layer "F.Fab")
		)
		(fp_line
			(start -0.12065 -0.305054)
			(end -0.12065 -0.2794)
			(stroke
				(width 0.1)
				(type default)
			)
			(layer "F.Fab")
		)
		(fp_line
			(start -0.67945 0.3048)
			(end -0.67945 -0.305054)
			(stroke
				(width 0.1)
				(type default)
			)
			(layer "F.Fab")
		)
		(fp_line
			(start -0.67945 -0.305054)
			(end -0.12065 -0.305054)
			(stroke
				(width 0.1)
				(type default)
			)
			(layer "F.Fab")
		)
		(pad "1" smd circle
			(at -0.40005 0 180)
			(size 0 0)
			(layers "F.Cu" "F.Mask" "F.Paste")
			(net "VSENSE_PVCCD_HV_CPU1_DN")
		)
		(pad "2" smd circle
			(at 0.40005 0 180)
			(size 0 0)
			(layers "F.Cu" "F.Mask" "F.Paste")
			(net "GND")
		)
	)
	(footprint ""
		(layer "F.Cu")
		(at 479.84537 -121.640092 -90)
		(property "Reference" "X36"
			(at 2.387092 -2.4003 90)
			(unlocked yes)
			(layer "F.SilkS")
			(effects
				(font
					(size 0.7874 0.5842)
					(thickness 0.1524)
				)
				(justify left)
			)
		)
		(property "Value" ""
			(at 0 0 270)
			(layer "F.Fab")
			(effects
				(font
					(size 1.27 1.27)
				)
			)
		)
		(property "Device Type" "TP_TDR_4P_FTS_TH-TP_TDR_4P_DIPA"
			(at 1.30175 1.27 0)
			(unlocked yes)
			(layer "F.Fab")
			(hide yes)
			(effects
				(font
					(size 0.635 0.4064)
					(thickness 0.1524)
				)
			)
		)
		(property "User Part Number" "N_A"
			(at 1.30175 1.27 0)
			(unlocked yes)
			(layer "Cmts.User")
			(hide yes)
			(effects
				(font
					(size 0.635 0.4064)
					(thickness 0.1524)
				)
			)
		)
		(duplicate_pad_numbers_are_jumpers no)
		(fp_line
			(start 0 3.81)
			(end 2.54 3.81)
			(stroke
				(width 0.1524)
				(type default)
			)
			(layer "F.SilkS")
		)
		(fp_line
			(start 2.54 3.81)
			(end 2.54 3.6703)
			(stroke
				(width 0.1524)
				(type default)
			)
			(layer "F.SilkS")
		)
		(fp_line
			(start 0 3.175)
			(end 0 3.81)
			(stroke
				(width 0.1524)
				(type default)
			)
			(layer "F.SilkS")
		)
		(fp_line
			(start 2.54 1.4097)
			(end 2.54 1.1303)
			(stroke
				(width 0.1524)
				(type default)
			)
			(layer "F.SilkS")
		)
		(fp_line
			(start 0 0.635)
			(end 0 1.905)
			(stroke
				(width 0.1524)
				(type default)
			)
			(layer "F.SilkS")
		)
		(fp_line
			(start 2.54 -1.1303)
			(end 2.54 -1.27)
			(stroke
				(width 0.1524)
				(type default)
			)
			(layer "F.SilkS")
		)
		(fp_line
			(start 0 -1.27)
			(end 0 -0.635)
			(stroke
				(width 0.1524)
				(type default)
			)
			(layer "F.SilkS")
		)
		(fp_line
			(start 2.54 -1.27)
			(end 0 -1.27)
			(stroke
				(width 0.1524)
				(type default)
			)
			(layer "F.SilkS")
		)
		(fp_poly
			(pts
				(xy -0.761746 0) (xy -2.285746 -0.762) (xy -2.285746 0.762)
			)
			(stroke
				(width 0)
				(type default)
			)
			(fill yes)
			(layer "F.SilkS")
		)
		(fp_line
			(start 0 3.81)
			(end 2.54 3.81)
			(stroke
				(width 0.1)
				(type default)
			)
			(layer "F.Fab")
		)
		(fp_line
			(start 2.54 3.81)
			(end 2.54 -1.27)
			(stroke
				(width 0.1)
				(type default)
			)
			(layer "F.Fab")
		)
		(fp_line
			(start 0 -1.27)
			(end 0 3.81)
			(stroke
				(width 0.1)
				(type default)
			)
			(layer "F.Fab")
		)
		(fp_line
			(start 2.54 -1.27)
			(end 0 -1.27)
			(stroke
				(width 0.1)
				(type default)
			)
			(layer "F.Fab")
		)
		(fp_poly
			(pts
				(xy -0.761746 0) (xy -2.285746 -0.762) (xy -2.285746 0.762)
			)
			(stroke
				(width 0)
				(type default)
			)
			(fill yes)
			(layer "F.Fab")
		)
		(pad "1" thru_hole circle
			(at 0 0 270)
			(size 1.0033 1.0033)
			(drill 0.249936)
			(layers "*.Cu" "*.Mask")
			(remove_unused_layers no)
			(net "TDR_DIFF_85_NECK_IN3_DP")
			(clearance 0.10795)
			(thermal_gap 0.10795)
			(padstack
				(mode front_inner_back)
				(layer "Inner"
					(shape circle)
					(size 0.8001 0.8001)
					(clearance 0.1524)
				)
				(layer "B.Cu"
					(shape circle)
					(size 1.0033 1.0033)
					(clearance 0.10795)
				)
			)
		)
		(pad "2" thru_hole circle
			(at 2.54 0 270)
			(size 1.9939 1.9939)
			(drill 0.249936)
			(layers "*.Cu" "*.Mask")
			(remove_unused_layers no)
			(net "T1_GND")
			(clearance 0.10795)
			(thermal_gap 0.10795)
			(padstack
				(mode front_inner_back)
				(layer "Inner"
					(shape circle)
					(size 0.8001 0.8001)
					(clearance 0.1524)
				)
				(layer "B.Cu"
					(shape circle)
					(size 1.9939 1.9939)
					(clearance 0.10795)
				)
			)
		)
		(pad "3" thru_hole circle
			(at 2.54 2.54 270)
			(size 1.9939 1.9939)
			(drill 0.249936)
			(layers "*.Cu" "*.Mask")
			(remove_unused_layers no)
			(net "T1_GND")
			(clearance 0.10795)
			(thermal_gap 0.10795)
			(padstack
				(mode front_inner_back)
				(layer "Inner"
					(shape circle)
					(size 0.8001 0.8001)
					(clearance 0.1524)
				)
				(layer "B.Cu"
					(shape circle)
					(size 1.9939 1.9939)
					(clearance 0.10795)
				)
			)
		)
		(pad "4" thru_hole circle
			(at 0 2.54 270)
			(size 1.0033 1.0033)
			(drill 0.249936)
			(layers "*.Cu" "*.Mask")
			(remove_unused_layers no)
			(net "TDR_DIFF_85_NECK_IN3_DN")
			(clearance 0.10795)
			(thermal_gap 0.10795)
			(padstack
				(mode front_inner_back)
				(layer "Inner"
					(shape circle)
					(size 0.8001 0.8001)
					(clearance 0.1524)
				)
				(layer "B.Cu"
					(shape circle)
					(size 1.0033 1.0033)
					(clearance 0.10795)
				)
			)
		)
	)
)
